# S9S_MB_2U (Grand Teton) — schematic netlist excerpt (pin names and nets, part order shuffled) for the footprints in the layout excerpt that follows; sources: Cadence DE-HDL packaged netlist, KiCad conversion of 03242023_DA0F0TMBIJ0_F0T_Motherboard_J_brd_V01_OCP.brd

PR1708  Q_RES  8.87K 1% EMPTY  pkg 0402LF  page 275 : A = PVCCINFAON_CPU0_LSET1 ; B = GND
C2451  Q_CAP  1000PF 50V 5% X7R  pkg 0402  page 292 : A = PVCCINFAON_CPU1_EN_R ; B = GND

(kicad_pcb
	(version 20260206)
	(generator "pcbnew")
	(generator_version "10.0")
	(general
		(thickness 1.6)
		(legacy_teardrops no)
	)
	(paper "A4")
	(title_block
		(title "03242023_DA0F0TMBIJ0_F0T_Motherboard_J_brd_V01_OCP.brd")
		(comment 1 "Grand Teton / footprints 3823-3824 of 6105")
	)
	(layers
		(0 "F.Cu" signal "TOP")
		(4 "In1.Cu" signal "GND")
		(6 "In2.Cu" signal "IN1")
		(8 "In3.Cu" signal "GND1")
		(10 "In4.Cu" signal "IN2")
		(12 "In5.Cu" signal "GND2")
		(14 "In6.Cu" signal "IN3")
		(16 "In7.Cu" signal "GND3")
		(18 "In8.Cu" signal "VCC")
		(20 "In9.Cu" signal "VCC1")
		(22 "In10.Cu" signal "GND4")
		(24 "In11.Cu" signal "IN4")
		(26 "In12.Cu" signal "GND5")
		(28 "In13.Cu" signal "IN5")
		(30 "In14.Cu" signal "GND6")
		(32 "In15.Cu" signal "IN6")
		(34 "In16.Cu" signal "GND7")
		(2 "B.Cu" signal "BOTTOM")
		(9 "F.Adhes" user "F.Adhesive")
		(11 "B.Adhes" user "B.Adhesive")
		(13 "F.Paste" user "Package Geometry/Pastemask Top")
		(15 "B.Paste" user "Package Geometry/Pastemask Bottom")
		(5 "F.SilkS" user "Ref Des/Silkscreen Top")
		(7 "B.SilkS" user "Ref Des/Silkscreen Bottom")
		(1 "F.Mask" user "Board Geometry/Soldermask Top")
		(3 "B.Mask" user "Board Geometry/Soldermask Bottom")
		(17 "Dwgs.User" user "User.Drawings")
		(19 "Cmts.User" user "User.Comments")
		(21 "Eco1.User" user "User.Eco1")
		(23 "Eco2.User" user "User.Eco2")
		(25 "Edge.Cuts" user "Board Geometry/Outline")
		(27 "Margin" user)
		(31 "F.CrtYd" user "Package Geometry/Place Bound Top")
		(29 "B.CrtYd" user "Package Geometry/Place Bound Bottom")
		(35 "F.Fab" user "Ref Des/Assembly Top")
		(33 "B.Fab" user "Ref Des/Assembly Bottom")
	)
	(footprint ""
		(layer "F.Cu")
		(at 421.15359 -172.113194 -90)
		(property "Reference" "PR1708"
			(at 0 0 270)
			(layer "F.SilkS")
			(hide yes)
			(effects
				(font
					(size 1.27 1.27)
				)
			)
		)
		(property "Value" ""
			(at 0 0 270)
			(layer "F.Fab")
			(effects
				(font
					(size 1.27 1.27)
				)
			)
		)
		(duplicate_pad_numbers_are_jumpers no)
		(fp_line
			(start -0.7874 0.4064)
			(end -0.7874 -0.4064)
			(stroke
				(width 0.1524)
				(type default)
			)
			(layer "F.SilkS")
		)
		(fp_line
			(start 0.7874 0.4064)
			(end -0.7874 0.4064)
			(stroke
				(width 0.1524)
				(type default)
			)
			(layer "F.SilkS")
		)
		(fp_line
			(start -0.7874 -0.4064)
			(end 0.7874 -0.4064)
			(stroke
				(width 0.1524)
				(type default)
			)
			(layer "F.SilkS")
		)
		(fp_line
			(start 0.7874 -0.4064)
			(end 0.7874 0.4064)
			(stroke
				(width 0.1524)
				(type default)
			)
			(layer "F.SilkS")
		)
		(fp_line
			(start -0.67945 0.3048)
			(end -0.67945 -0.305054)
			(stroke
				(width 0.1)
				(type default)
			)
			(layer "F.Fab")
		)
		(fp_line
			(start -0.12065 0.3048)
			(end -0.67945 0.3048)
			(stroke
				(width 0.1)
				(type default)
			)
			(layer "F.Fab")
		)
		(fp_line
			(start 0.120396 0.3048)
			(end 0.120396 0.2794)
			(stroke
				(width 0.1)
				(type default)
			)
			(layer "F.Fab")
		)
		(fp_line
			(start 0.67945 0.3048)
			(end 0.120396 0.3048)
			(stroke
				(width 0.1)
				(type default)
			)
			(layer "F.Fab")
		)
		(fp_line
			(start -0.12065 0.2794)
			(end -0.12065 0.3048)
			(stroke
				(width 0.1)
				(type default)
			)
			(layer "F.Fab")
		)
		(fp_line
			(start 0.120396 0.2794)
			(end -0.12065 0.2794)
			(stroke
				(width 0.1)
				(type default)
			)
			(layer "F.Fab")
		)
		(fp_line
			(start -0.12065 -0.2794)
			(end 0.12065 -0.2794)
			(stroke
				(width 0.1)
				(type default)
			)
			(layer "F.Fab")
		)
		(fp_line
			(start 0.12065 -0.2794)
			(end 0.12065 -0.3048)
			(stroke
				(width 0.1)
				(type default)
			)
			(layer "F.Fab")
		)
		(fp_line
			(start 0.12065 -0.3048)
			(end 0.67945 -0.3048)
			(stroke
				(width 0.1)
				(type default)
			)
			(layer "F.Fab")
		)
		(fp_line
			(start 0.67945 -0.3048)
			(end 0.67945 0.3048)
			(stroke
				(width 0.1)
				(type default)
			)
			(layer "F.Fab")
		)
		(fp_line
			(start -0.67945 -0.305054)
			(end -0.12065 -0.305054)
			(stroke
				(width 0.1)
				(type default)
			)
			(layer "F.Fab")
		)
		(fp_line
			(start -0.12065 -0.305054)
			(end -0.12065 -0.2794)
			(stroke
				(width 0.1)
				(type default)
			)
			(layer "F.Fab")
		)
		(pad "1" smd circle
			(at -0.40005 0 270)
			(size 0 0)
			(layers "F.Cu" "F.Mask" "F.Paste")
			(net "PVCCINFAON_CPU0_LSET1")
		)
		(pad "2" smd circle
			(at 0.40005 0 270)
			(size 0 0)
			(layers "F.Cu" "F.Mask" "F.Paste")
			(net "GND")
		)
	)
	(footprint ""
		(layer "F.Cu")
		(at 36.956238 -127.71374)
		(property "Reference" "C2451"
			(at 0 0 0)
			(layer "F.SilkS")
			(hide yes)
			(effects
				(font
					(size 1.27 1.27)
				)
			)
		)
		(property "Value" ""
			(at 0 0 0)
			(layer "F.Fab")
			(effects
				(font
					(size 1.27 1.27)
				)
			)
		)
		(duplicate_pad_numbers_are_jumpers no)
		(fp_line
			(start -0.7874 -0.4064)
			(end 0.7874 -0.4064)
			(stroke
				(width 0.1524)
				(type default)
			)
			(layer "F.SilkS")
		)
		(fp_line
			(start -0.7874 0.4064)
			(end -0.7874 -0.4064)
			(stroke
				(width 0.1524)
				(type default)
			)
			(layer "F.SilkS")
		)
		(fp_line
			(start 0.7874 -0.4064)
			(end 0.7874 0.4064)
			(stroke
				(width 0.1524)
				(type default)
			)
			(layer "F.SilkS")
		)
		(fp_line
			(start 0.7874 0.4064)
			(end -0.7874 0.4064)
			(stroke
				(width 0.1524)
				(type default)
			)
			(layer "F.SilkS")
		)
		(fp_line
			(start -0.67945 -0.305054)
			(end -0.12065 -0.305054)
			(stroke
				(width 0.1)
				(type default)
			)
			(layer "F.Fab")
		)
		(fp_line
			(start -0.67945 0.3048)
			(end -0.67945 -0.305054)
			(stroke
				(width 0.1)
				(type default)
			)
			(layer "F.Fab")
		)
		(fp_line
			(start -0.12065 -0.305054)
			(end -0.12065 -0.2794)
			(stroke
				(width 0.1)
				(type default)
			)
			(layer "F.Fab")
		)
		(fp_line
			(start -0.12065 -0.2794)
			(end 0.12065 -0.2794)
			(stroke
				(width 0.1)
				(type default)
			)
			(layer "F.Fab")
		)
		(fp_line
			(start -0.12065 0.2794)
			(end -0.12065 0.3048)
			(stroke
				(width 0.1)
				(type default)
			)
			(layer "F.Fab")
		)
		(fp_line
			(start -0.12065 0.3048)
			(end -0.67945 0.3048)
			(stroke
				(width 0.1)
				(type default)
			)
			(layer "F.Fab")
		)
		(fp_line
			(start 0.120396 0.2794)
			(end -0.12065 0.2794)
			(stroke
				(width 0.1)
				(type default)
			)
			(layer "F.Fab")
		)
		(fp_line
			(start 0.120396 0.3048)
			(end 0.120396 0.2794)
			(stroke
				(width 0.1)
				(type default)
			)
			(layer "F.Fab")
		)
		(fp_line
			(start 0.12065 -0.3048)
			(end 0.67945 -0.3048)
			(stroke
				(width 0.1)
				(type default)
			)
			(layer "F.Fab")
		)
		(fp_line
			(start 0.12065 -0.2794)
			(end 0.12065 -0.3048)
			(stroke
				(width 0.1)
				(type default)
			)
			(layer "F.Fab")
		)
		(fp_line
			(start 0.67945 -0.3048)
			(end 0.67945 0.3048)
			(stroke
				(width 0.1)
				(type default)
			)
			(layer "F.Fab")
		)
		(fp_line
			(start 0.67945 0.3048)
			(end 0.120396 0.3048)
			(stroke
				(width 0.1)
				(type default)
			)
			(layer "F.Fab")
		)
		(pad "1" smd circle
			(at -0.40005 0)
			(size 0 0)
			(layers "F.Cu" "F.Mask" "F.Paste")
			(net "PVCCINFAON_CPU1_EN_R")
		)
		(pad "2" smd circle
			(at 0.40005 0)
			(size 0 0)
			(layers "F.Cu" "F.Mask" "F.Paste")
			(net "GND")
		)
	)
)
